(kicad_pcb
	(version 20260206)
	(generator "pcbnew")
	(generator_version "10.0")
	(general
		(thickness 1.6)
		(legacy_teardrops no)
	)
	(paper "A4")
	(title_block
		(title "01162023_DA0F0TEBIF0_F0T_Expander_BD_F_brd_V02_OCP.brd")
		(comment 1 "Grand Teton / footprints 1278-1283 of 9728")
	)
	(layers
		(0 "F.Cu" signal "TOP")
		(4 "In1.Cu" signal "GND")
		(6 "In2.Cu" signal "VCC")
		(8 "In3.Cu" signal "VCC1")
		(10 "In4.Cu" signal "GND1")
		(12 "In5.Cu" signal "IN1")
		(14 "In6.Cu" signal "GND2")
		(16 "In7.Cu" signal "IN2")
		(18 "In8.Cu" signal "GND3")
		(20 "In9.Cu" signal "IN3")
		(22 "In10.Cu" signal "GND4")
		(24 "In11.Cu" signal "IN4")
		(26 "In12.Cu" signal "GND5")
		(28 "In13.Cu" signal "IN5")
		(30 "In14.Cu" signal "GND6")
		(32 "In15.Cu" signal "IN6")
		(34 "In16.Cu" signal "GND7")
		(2 "B.Cu" signal "BOTTOM")
		(9 "F.Adhes" user "F.Adhesive")
		(11 "B.Adhes" user "B.Adhesive")
		(13 "F.Paste" user "Package Geometry/Pastemask Top")
		(15 "B.Paste" user "Package Geometry/Pastemask Bottom")
		(5 "F.SilkS" user "Ref Des/Silkscreen Top")
		(7 "B.SilkS" user "Ref Des/Silkscreen Bottom")
		(1 "F.Mask" user "Board Geometry/Soldermask Top")
		(3 "B.Mask" user "Board Geometry/Soldermask Bottom")
		(17 "Dwgs.User" user "User.Drawings")
		(19 "Cmts.User" user "User.Comments")
		(21 "Eco1.User" user "User.Eco1")
		(23 "Eco2.User" user "User.Eco2")
		(25 "Edge.Cuts" user "Board Geometry/Outline")
		(27 "Margin" user)
		(31 "F.CrtYd" user "Package Geometry/Place Bound Top")
		(29 "B.CrtYd" user "Package Geometry/Place Bound Bottom")
		(35 "F.Fab" user "Ref Des/Assembly Top")
		(33 "B.Fab" user "Ref Des/Assembly Bottom")
	)
	(footprint ""
		(layer "F.Cu")
		(at 78.345792 -447.279014)
		(property "Reference" "X3"
			(at -0.1778 -1.92913 0)
			(unlocked yes)
			(layer "F.SilkS")
			(effects
				(font
					(size 0.7874 0.5842)
					(thickness 0.1524)
				)
				(justify left)
			)
		)
		(property "Value" ""
			(at 0 0 0)
			(layer "F.Fab")
			(effects
				(font
					(size 1.27 1.27)
				)
			)
		)
		(property "Device Type" "TP_TDR_4P_FTS_MPKT4_H025P0200_IO_TP15_TP_TDR_4P_DIP"
			(at 1.30175 1.27 90)
			(unlocked yes)
			(layer "F.Fab")
			(hide yes)
			(effects
				(font
					(size 0.635 0.4064)
					(thickness 0.1524)
				)
			)
		)
		(property "User Part Number" "TP15"
			(at 1.30175 1.27 90)
			(unlocked yes)
			(layer "Cmts.User")
			(hide yes)
			(effects
				(font
					(size 0.635 0.4064)
					(thickness 0.1524)
				)
			)
		)
		(duplicate_pad_numbers_are_jumpers no)
		(fp_line
			(start 0 -1.27)
			(end 0 -0.635)
			(stroke
				(width 0.1524)
				(type default)
			)
			(layer "F.SilkS")
		)
		(fp_line
			(start 0 0.635)
			(end 0 1.905)
			(stroke
				(width 0.1524)
				(type default)
			)
			(layer "F.SilkS")
		)
		(fp_line
			(start 0 3.175)
			(end 0 3.81)
			(stroke
				(width 0.1524)
				(type default)
			)
			(layer "F.SilkS")
		)
		(fp_line
			(start 0 3.81)
			(end 2.54 3.81)
			(stroke
				(width 0.1524)
				(type default)
			)
			(layer "F.SilkS")
		)
		(fp_line
			(start 2.54 -1.27)
			(end 0 -1.27)
			(stroke
				(width 0.1524)
				(type default)
			)
			(layer "F.SilkS")
		)
		(fp_line
			(start 2.54 -1.1303)
			(end 2.54 -1.27)
			(stroke
				(width 0.1524)
				(type default)
			)
			(layer "F.SilkS")
		)
		(fp_line
			(start 2.54 1.4097)
			(end 2.54 1.1303)
			(stroke
				(width 0.1524)
				(type default)
			)
			(layer "F.SilkS")
		)
		(fp_line
			(start 2.54 3.81)
			(end 2.54 3.6703)
			(stroke
				(width 0.1524)
				(type default)
			)
			(layer "F.SilkS")
		)
		(fp_poly
			(pts
				(xy -0.761746 0) (xy -2.285746 -0.762) (xy -2.285746 0.762)
			)
			(stroke
				(width 0)
				(type default)
			)
			(fill yes)
			(layer "F.SilkS")
		)
		(fp_line
			(start 0 -1.27)
			(end 0 3.81)
			(stroke
				(width 0.1)
				(type default)
			)
			(layer "F.Fab")
		)
		(fp_line
			(start 0 3.81)
			(end 2.54 3.81)
			(stroke
				(width 0.1)
				(type default)
			)
			(layer "F.Fab")
		)
		(fp_line
			(start 2.54 -1.27)
			(end 0 -1.27)
			(stroke
				(width 0.1)
				(type default)
			)
			(layer "F.Fab")
		)
		(fp_line
			(start 2.54 3.81)
			(end 2.54 -1.27)
			(stroke
				(width 0.1)
				(type default)
			)
			(layer "F.Fab")
		)
		(fp_poly
			(pts
				(xy -0.761746 0) (xy -2.285746 -0.762) (xy -2.285746 0.762)
			)
			(stroke
				(width 0)
				(type default)
			)
			(fill yes)
			(layer "F.Fab")
		)
		(pad "1" thru_hole circle
			(at 0 0)
			(size 1.0033 1.0033)
			(drill 0.249936)
			(layers "*.Cu" "*.Mask")
			(remove_unused_layers no)
			(net "TDR_DIFF_85_TOP_DIN")
			(clearance 0.10795)
			(thermal_gap 0.10795)
			(padstack
				(mode front_inner_back)
				(layer "Inner"
					(shape circle)
					(size 0.8001 0.8001)
					(clearance 0.1524)
				)
				(layer "B.Cu"
					(shape circle)
					(size 1.0033 1.0033)
					(clearance 0.10795)
				)
			)
		)
		(pad "2" thru_hole circle
			(at 2.54 0)
			(size 1.9939 1.9939)
			(drill 0.249936)
			(layers "*.Cu" "*.Mask")
			(remove_unused_layers no)
			(net "COUPON_GND1")
			(clearance 0.10795)
			(thermal_gap 0.10795)
			(padstack
				(mode front_inner_back)
				(layer "Inner"
					(shape circle)
					(size 0.8001 0.8001)
					(clearance 0.1524)
				)
				(layer "B.Cu"
					(shape circle)
					(size 1.9939 1.9939)
					(clearance 0.10795)
				)
			)
		)
		(pad "3" thru_hole circle
			(at 2.54 2.54)
			(size 1.9939 1.9939)
			(drill 0.249936)
			(layers "*.Cu" "*.Mask")
			(remove_unused_layers no)
			(net "COUPON_GND1")
			(clearance 0.10795)
			(thermal_gap 0.10795)
			(padstack
				(mode front_inner_back)
				(layer "Inner"
					(shape circle)
					(size 0.8001 0.8001)
					(clearance 0.1524)
				)
				(layer "B.Cu"
					(shape circle)
					(size 1.9939 1.9939)
					(clearance 0.10795)
				)
			)
		)
		(pad "4" thru_hole circle
			(at 0 2.54)
			(size 1.0033 1.0033)
			(drill 0.249936)
			(layers "*.Cu" "*.Mask")
			(remove_unused_layers no)
			(net "TDR_DIFF_85_TOP_DIP")
			(clearance 0.10795)
			(thermal_gap 0.10795)
			(padstack
				(mode front_inner_back)
				(layer "Inner"
					(shape circle)
					(size 0.8001 0.8001)
					(clearance 0.1524)
				)
				(layer "B.Cu"
					(shape circle)
					(size 1.0033 1.0033)
					(clearance 0.10795)
				)
			)
		)
	)
	(footprint ""
		(layer "F.Cu")
		(at 188.534548 -34.546286 180)
		(property "Reference" "C292"
			(at 0 0 180)
			(layer "F.SilkS")
			(hide yes)
			(effects
				(font
					(size 1.27 1.27)
				)
			)
		)
		(property "Value" ""
			(at 0 0 180)
			(layer "F.Fab")
			(effects
				(font
					(size 1.27 1.27)
				)
			)
		)
		(duplicate_pad_numbers_are_jumpers no)
		(fp_line
			(start 0.299974 0.150114)
			(end -0.299974 0.150114)
			(stroke
				(width 0.1)
				(type default)
			)
			(layer "F.Fab")
		)
		(fp_line
			(start 0.299974 -0.150114)
			(end 0.299974 0.150114)
			(stroke
				(width 0.1)
				(type default)
			)
			(layer "F.Fab")
		)
		(fp_line
			(start -0.299974 0.150114)
			(end -0.299974 -0.150114)
			(stroke
				(width 0.1)
				(type default)
			)
			(layer "F.Fab")
		)
		(fp_line
			(start -0.299974 -0.150114)
			(end 0.299974 -0.150114)
			(stroke
				(width 0.1)
				(type default)
			)
			(layer "F.Fab")
		)
		(pad "1" smd rect
			(at -0.2667 0 180)
			(size 0.3048 0.381)
			(layers "F.Cu" "F.Mask" "F.Paste")
			(net "P5E_PEX1_STN2_TX_DP<39>")
		)
		(pad "2" smd rect
			(at 0.2667 0 180)
			(size 0.3048 0.381)
			(layers "F.Cu" "F.Mask" "F.Paste")
			(net "P5E_PEX1_STN2_TX_C_DP<39>")
		)
	)
	(footprint ""
		(layer "F.Cu")
		(at 402.909024 18.035524)
		(property "Reference" "DE05F_2"
			(at -3.6068 -2.962148 0)
			(unlocked yes)
			(layer "F.SilkS")
			(effects
				(font
					(size 0.7874 0.5842)
					(thickness 0.1524)
				)
				(justify left)
			)
		)
		(property "Value" ""
			(at 0 0 0)
			(layer "F.Fab")
			(effects
				(font
					(size 1.27 1.27)
				)
			)
		)
		(duplicate_pad_numbers_are_jumpers no)
		(fp_line
			(start -1.2192 -2.1082)
			(end 1.2192 -2.1082)
			(stroke
				(width 0.1524)
				(type default)
			)
			(layer "F.SilkS")
		)
		(fp_line
			(start -1.2192 2.1082)
			(end -1.2192 -2.1082)
			(stroke
				(width 0.1524)
				(type default)
			)
			(layer "F.SilkS")
		)
		(fp_line
			(start 1.2192 -2.1082)
			(end 1.2192 2.1082)
			(stroke
				(width 0.1524)
				(type default)
			)
			(layer "F.SilkS")
		)
		(fp_line
			(start 1.2192 2.1082)
			(end -1.2192 2.1082)
			(stroke
				(width 0.1524)
				(type default)
			)
			(layer "F.SilkS")
		)
		(pad "" np_thru_hole circle
			(at -2.8829 -1.27 270)
			(size 1.0414 1.0414)
			(drill 1.0414)
			(layers "*.Cu" "*.Mask")
			(clearance 0.381)
			(thermal_gap 0.381)
		)
		(pad "" np_thru_hole circle
			(at -2.8829 1.27 270)
			(size 1.0414 1.0414)
			(drill 1.0414)
			(layers "*.Cu" "*.Mask")
			(clearance 0.381)
			(thermal_gap 0.381)
		)
		(pad "" np_thru_hole circle
			(at 3.4671 -1.27 270)
			(size 1.0414 1.0414)
			(drill 1.0414)
			(layers "*.Cu" "*.Mask")
			(clearance 0.381)
			(thermal_gap 0.381)
		)
		(pad "" np_thru_hole circle
			(at 3.4671 1.27 270)
			(size 1.0414 1.0414)
			(drill 1.0414)
			(layers "*.Cu" "*.Mask")
			(clearance 0.381)
			(thermal_gap 0.381)
		)
		(pad "1" smd rect
			(at 0.8255 -0.249936 270)
			(size 0.3048 0.508)
			(layers "F.Cu" "F.Mask" "F.Paste")
			(net "85_5INCH_IN3_DN")
		)
		(pad "2" smd rect
			(at 0.8255 0.249936 270)
			(size 0.3048 0.508)
			(layers "F.Cu" "F.Mask" "F.Paste")
			(net "85_5INCH_IN3_DP")
		)
		(pad "3" smd circle
			(at 0 0)
			(size 0 0)
			(layers "F.Cu" "F.Mask" "F.Paste")
			(net "COUPON_GND2")
		)
		(zone
			(layer "F.Cu")
			(hatch none 0.5)
			(connect_pads
				(clearance 0)
			)
			(min_thickness 0.25)
			(keepout
				(tracks not_allowed)
				(vias allowed)
				(pads allowed)
				(copperpour not_allowed)
				(footprints allowed)
			)
			(placement
				(enabled no)
				(sheetname "")
			)
			(fill
				(thermal_gap 0.5)
				(thermal_bridge_width 0.5)
				(island_removal_mode 0)
			)
			(polygon
				(pts
					(xy 404.026624 17.486884) (xy 404.026624 17.582388) (xy 403.429724 17.582388) (xy 403.429724 17.988788)
					(xy 404.026624 17.988788) (xy 404.026624 18.08226) (xy 403.429724 18.08226) (xy 403.429724 18.48866)
					(xy 404.026624 18.48866) (xy 404.026624 18.584164) (xy 403.328124 18.584164) (xy 403.328124 17.486884)
				)
			)
		)
		(zone
			(layers "F.Cu" "B.Cu" "In1.Cu" "In2.Cu" "In3.Cu" "In4.Cu" "In5.Cu" "In6.Cu"
				"In7.Cu" "In8.Cu" "In9.Cu" "In10.Cu" "In11.Cu" "In12.Cu" "In13.Cu" "In14.Cu"
				"In15.Cu" "In16.Cu"
			)
			(hatch none 0.5)
			(connect_pads
				(clearance 0)
			)
			(min_thickness 0.25)
			(keepout
				(tracks not_allowed)
				(vias allowed)
				(pads allowed)
				(copperpour not_allowed)
				(footprints allowed)
			)
			(placement
				(enabled no)
				(sheetname "")
			)
			(fill
				(thermal_gap 0.5)
				(thermal_bridge_width 0.5)
				(island_removal_mode 0)
			)
			(polygon
				(pts
					(arc
						(start 400.953224 16.765524)
						(mid 399.099024 16.765524)
						(end 400.953224 16.765524)
					)
				)
			)
		)
		(zone
			(layers "F.Cu" "B.Cu" "In1.Cu" "In2.Cu" "In3.Cu" "In4.Cu" "In5.Cu" "In6.Cu"
				"In7.Cu" "In8.Cu" "In9.Cu" "In10.Cu" "In11.Cu" "In12.Cu" "In13.Cu" "In14.Cu"
				"In15.Cu" "In16.Cu"
			)
			(hatch none 0.5)
			(connect_pads
				(clearance 0)
			)
			(min_thickness 0.25)
			(keepout
				(tracks not_allowed)
				(vias allowed)
				(pads allowed)
				(copperpour not_allowed)
				(footprints allowed)
			)
			(placement
				(enabled no)
				(sheetname "")
			)
			(fill
				(thermal_gap 0.5)
				(thermal_bridge_width 0.5)
				(island_removal_mode 0)
			)
			(polygon
				(pts
					(arc
						(start 400.953224 19.305524)
						(mid 399.099024 19.305524)
						(end 400.953224 19.305524)
					)
				)
			)
		)
		(zone
			(layers "F.Cu" "B.Cu" "In1.Cu" "In2.Cu" "In3.Cu" "In4.Cu" "In5.Cu" "In6.Cu"
				"In7.Cu" "In8.Cu" "In9.Cu" "In10.Cu" "In11.Cu" "In12.Cu" "In13.Cu" "In14.Cu"
				"In15.Cu" "In16.Cu"
			)
			(hatch none 0.5)
			(connect_pads
				(clearance 0)
			)
			(min_thickness 0.25)
			(keepout
				(tracks not_allowed)
				(vias allowed)
				(pads allowed)
				(copperpour not_allowed)
				(footprints allowed)
			)
			(placement
				(enabled no)
				(sheetname "")
			)
			(fill
				(thermal_gap 0.5)
				(thermal_bridge_width 0.5)
				(island_removal_mode 0)
			)
			(polygon
				(pts
					(arc
						(start 407.303224 16.765524)
						(mid 405.449024 16.765524)
						(end 407.303224 16.765524)
					)
				)
			)
		)
		(zone
			(layers "F.Cu" "B.Cu" "In1.Cu" "In2.Cu" "In3.Cu" "In4.Cu" "In5.Cu" "In6.Cu"
				"In7.Cu" "In8.Cu" "In9.Cu" "In10.Cu" "In11.Cu" "In12.Cu" "In13.Cu" "In14.Cu"
				"In15.Cu" "In16.Cu"
			)
			(hatch none 0.5)
			(connect_pads
				(clearance 0)
			)
			(min_thickness 0.25)
			(keepout
				(tracks not_allowed)
				(vias allowed)
				(pads allowed)
				(copperpour not_allowed)
				(footprints allowed)
			)
			(placement
				(enabled no)
				(sheetname "")
			)
			(fill
				(thermal_gap 0.5)
				(thermal_bridge_width 0.5)
				(island_removal_mode 0)
			)
			(polygon
				(pts
					(arc
						(start 407.303224 19.305524)
						(mid 405.449024 19.305524)
						(end 407.303224 19.305524)
					)
				)
			)
		)
	)
	(footprint ""
		(layer "F.Cu")
		(at 58.995056 -100.766372 180)
		(property "Reference" "R78"
			(at 0 0 180)
			(layer "F.SilkS")
			(hide yes)
			(effects
				(font
					(size 1.27 1.27)
				)
			)
		)
		(property "Value" ""
			(at 0 0 180)
			(layer "F.Fab")
			(effects
				(font
					(size 1.27 1.27)
				)
			)
		)
		(duplicate_pad_numbers_are_jumpers no)
		(fp_line
			(start 0.7874 0.4064)
			(end -0.7874 0.4064)
			(stroke
				(width 0.1524)
				(type default)
			)
			(layer "F.SilkS")
		)
		(fp_line
			(start 0.7874 -0.4064)
			(end 0.7874 0.4064)
			(stroke
				(width 0.1524)
				(type default)
			)
			(layer "F.SilkS")
		)
		(fp_line
			(start -0.7874 0.4064)
			(end -0.7874 -0.4064)
			(stroke
				(width 0.1524)
				(type default)
			)
			(layer "F.SilkS")
		)
		(fp_line
			(start -0.7874 -0.4064)
			(end 0.7874 -0.4064)
			(stroke
				(width 0.1524)
				(type default)
			)
			(layer "F.SilkS")
		)
		(fp_line
			(start 0.67945 0.3048)
			(end 0.120396 0.3048)
			(stroke
				(width 0.1)
				(type default)
			)
			(layer "F.Fab")
		)
		(fp_line
			(start 0.67945 -0.3048)
			(end 0.67945 0.3048)
			(stroke
				(width 0.1)
				(type default)
			)
			(layer "F.Fab")
		)
		(fp_line
			(start 0.12065 -0.2794)
			(end 0.12065 -0.3048)
			(stroke
				(width 0.1)
				(type default)
			)
			(layer "F.Fab")
		)
		(fp_line
			(start 0.12065 -0.3048)
			(end 0.67945 -0.3048)
			(stroke
				(width 0.1)
				(type default)
			)
			(layer "F.Fab")
		)
		(fp_line
			(start 0.120396 0.3048)
			(end 0.120396 0.2794)
			(stroke
				(width 0.1)
				(type default)
			)
			(layer "F.Fab")
		)
		(fp_line
			(start 0.120396 0.2794)
			(end -0.12065 0.2794)
			(stroke
				(width 0.1)
				(type default)
			)
			(layer "F.Fab")
		)
		(fp_line
			(start -0.12065 0.3048)
			(end -0.67945 0.3048)
			(stroke
				(width 0.1)
				(type default)
			)
			(layer "F.Fab")
		)
		(fp_line
			(start -0.12065 0.2794)
			(end -0.12065 0.3048)
			(stroke
				(width 0.1)
				(type default)
			)
			(layer "F.Fab")
		)
		(fp_line
			(start -0.12065 -0.2794)
			(end 0.12065 -0.2794)
			(stroke
				(width 0.1)
				(type default)
			)
			(layer "F.Fab")
		)
		(fp_line
			(start -0.12065 -0.305054)
			(end -0.12065 -0.2794)
			(stroke
				(width 0.1)
				(type default)
			)
			(layer "F.Fab")
		)
		(fp_line
			(start -0.67945 0.3048)
			(end -0.67945 -0.305054)
			(stroke
				(width 0.1)
				(type default)
			)
			(layer "F.Fab")
		)
		(fp_line
			(start -0.67945 -0.305054)
			(end -0.12065 -0.305054)
			(stroke
				(width 0.1)
				(type default)
			)
			(layer "F.Fab")
		)
		(pad "1" smd circle
			(at -0.40005 0 180)
			(size 0 0)
			(layers "F.Cu" "F.Mask" "F.Paste")
			(net "NIC1_SLOT_ID1")
		)
		(pad "2" smd circle
			(at 0.40005 0 180)
			(size 0 0)
			(layers "F.Cu" "F.Mask" "F.Paste")
			(net "P3V3_NIC1")
		)
	)
	(footprint ""
		(layer "F.Cu")
		(at 112.85728 -313.620404)
		(property "Reference" "R5786"
			(at 0 0 0)
			(layer "F.SilkS")
			(hide yes)
			(effects
				(font
					(size 1.27 1.27)
				)
			)
		)
		(property "Value" ""
			(at 0 0 0)
			(layer "F.Fab")
			(effects
				(font
					(size 1.27 1.27)
				)
			)
		)
		(duplicate_pad_numbers_are_jumpers no)
		(fp_line
			(start -2.576322 -1.1303)
			(end 2.576322 -1.1303)
			(stroke
				(width 0.1524)
				(type default)
			)
			(layer "F.SilkS")
		)
		(fp_line
			(start -2.576322 1.1303)
			(end -2.576322 -1.1303)
			(stroke
				(width 0.1524)
				(type default)
			)
			(layer "F.SilkS")
		)
		(fp_line
			(start 2.576322 -1.1303)
			(end 2.576322 1.1303)
			(stroke
				(width 0.1524)
				(type default)
			)
			(layer "F.SilkS")
		)
		(fp_line
			(start 2.576322 1.1303)
			(end -2.576322 1.1303)
			(stroke
				(width 0.1524)
				(type default)
			)
			(layer "F.SilkS")
		)
		(fp_line
			(start -1.649984 -0.899922)
			(end -1.649984 0.899922)
			(stroke
				(width 0.1)
				(type default)
			)
			(layer "F.Fab")
		)
		(fp_line
			(start -1.649984 0.899922)
			(end 1.649984 0.899922)
			(stroke
				(width 0.1)
				(type default)
			)
			(layer "F.Fab")
		)
		(fp_line
			(start 1.649984 -0.899922)
			(end -1.649984 -0.899922)
			(stroke
				(width 0.1)
				(type default)
			)
			(layer "F.Fab")
		)
		(fp_line
			(start 1.649984 0.899922)
			(end 1.649984 -0.899922)
			(stroke
				(width 0.1)
				(type default)
			)
			(layer "F.Fab")
		)
		(pad "1A" smd rect
			(at -1.700022 0)
			(size 1.4986 2.0066)
			(layers "F.Cu" "F.Mask" "F.Paste")
			(net "P0V8_PEX0")
		)
		(pad "1B" smd rect
			(at -1.077722 0)
			(size 0.254 0.508)
			(layers "F.Cu" "F.Mask" "F.Paste")
			(net "P0V8_PEX0")
		)
		(pad "2A" smd rect
			(at 1.700022 0)
			(size 1.4986 2.0066)
			(layers "F.Cu" "F.Mask" "F.Paste")
			(net "P0V8_SERDES_VDDA_PEX0")
		)
		(pad "2B" smd rect
			(at 1.077722 0)
			(size 0.254 0.508)
			(layers "F.Cu" "F.Mask" "F.Paste")
			(net "P0V8_SERDES_VDDA_PEX0")
		)
	)
	(footprint ""
		(layer "F.Cu")
		(at 381.620014 -20.72005)
		(property "Reference" "H115"
			(at 1.578864 -2.588768 0)
			(unlocked yes)
			(layer "B.SilkS")
			(effects
				(font
					(size 0.7874 0.5842)
					(thickness 0.1524)
				)
				(justify left mirror)
			)
		)
		(property "Value" ""
			(at 0 0 0)
			(layer "F.Fab")
			(effects
				(font
					(size 1.27 1.27)
				)
			)
		)
		(duplicate_pad_numbers_are_jumpers no)
		(pad "1" thru_hole rect
			(at 0 0)
			(size 4.2164 5.0038)
			(drill 2.0066
				(offset 0.099822 0)
			)
			(layers "*.Cu" "*.Mask")
			(remove_unused_layers no)
			(net "Net_8548")
			(clearance -0.8509)
			(padstack
				(mode front_inner_back)
				(layer "Inner"
					(shape circle)
					(size 4.0132 4.0132)
					(clearance -0.7493)
				)
				(layer "B.Cu"
					(shape circle)
					(size 4.0132 4.0132)
					(clearance -0.7493)
				)
			)
		)
	)
)
